(kicad_pcb
	(version 20260206)
	(generator "pcbnew")
	(generator_version "10.0")
	(general
		(thickness 1.6)
		(legacy_teardrops no)
	)
	(paper "A4")
	(title_block
		(title "pdpb — Lightning_PDPB_BRD.brd")
		(comment 1 "Lightning (Wiwynn / Facebook NVMe JBOF) / footprints 876-882 of 1140")
	)
	(layers
		(0 "F.Cu" signal "TOP")
		(4 "In1.Cu" signal "L2GND")
		(6 "In2.Cu" signal "L3")
		(8 "In3.Cu" signal "L4VCC")
		(10 "In4.Cu" signal "L5VCC")
		(12 "In5.Cu" signal "L6")
		(14 "In6.Cu" signal "L7GND")
		(2 "B.Cu" signal "BOTTOM")
		(9 "F.Adhes" user "F.Adhesive")
		(11 "B.Adhes" user "B.Adhesive")
		(13 "F.Paste" user "Package Geometry/Pastemask Top")
		(15 "B.Paste" user "Package Geometry/Pastemask Bottom")
		(5 "F.SilkS" user "Ref Des/Silkscreen Top")
		(7 "B.SilkS" user "Ref Des/Silkscreen Bottom")
		(1 "F.Mask" user "Board Geometry/Soldermask Top")
		(3 "B.Mask" user "Board Geometry/Soldermask Bottom")
		(17 "Dwgs.User" user "User.Drawings")
		(19 "Cmts.User" user "User.Comments")
		(21 "Eco1.User" user "User.Eco1")
		(23 "Eco2.User" user "User.Eco2")
		(25 "Edge.Cuts" user "Board Geometry/Outline")
		(27 "Margin" user)
		(31 "F.CrtYd" user "Package Geometry/Place Bound Top")
		(29 "B.CrtYd" user "Package Geometry/Place Bound Bottom")
		(35 "F.Fab" user "Ref Des/Assembly Top")
		(33 "B.Fab" user "Ref Des/Assembly Bottom")
	)
	(footprint ""
		(layer "F.Cu")
		(at 38.989 -144.653 90)
		(property "Reference" "C9526"
			(at 0 0 90)
			(layer "F.SilkS")
			(hide yes)
			(effects
				(font
					(size 1.27 1.27)
				)
			)
		)
		(property "Value" "SCD1U16V2KX-3GP"
			(at 1.1811 -2.7051 90)
			(unlocked yes)
			(layer "F.Fab")
			(hide yes)
			(effects
				(font
					(size 1.016 1.016)
					(thickness 0.1524)
				)
			)
		)
		(property "Device Type" "C402H22"
			(at 1.1811 -4.2291 90)
			(unlocked yes)
			(layer "F.Fab")
			(hide yes)
			(effects
				(font
					(size 1.016 1.016)
					(thickness 0.1524)
				)
			)
		)
		(duplicate_pad_numbers_are_jumpers no)
		(fp_rect
			(start -0.4318 0.9525)
			(end 0.4318 -0.9525)
			(stroke
				(width 0)
				(type default)
			)
			(fill no)
			(layer "F.CrtYd")
		)
		(fp_rect
			(start -0.4318 0.9525)
			(end 0.4318 -0.9525)
			(stroke
				(width 0)
				(type default)
			)
			(fill no)
			(layer "F.Fab")
		)
		(pad "1" smd custom
			(at 0 -0.4445 90)
			(size 0.1524 0.1524)
			(layers "F.Cu" "F.Mask" "F.Paste")
			(net "P3V3")
			(options
				(clearance outline)
				(anchor circle)
			)
			(primitives
				(gr_poly
					(pts
						(arc
							(start 0.3048 -0.2032)
							(mid 0.275042 -0.275042)
							(end 0.2032 -0.3048)
						)
						(arc
							(start -0.2032 -0.3048)
							(mid -0.275042 -0.275042)
							(end -0.3048 -0.2032)
						)
						(arc
							(start -0.3048 0.2032)
							(mid -0.275042 0.275042)
							(end -0.2032 0.3048)
						)
						(arc
							(start 0.2032 0.3048)
							(mid 0.275042 0.275042)
							(end 0.3048 0.2032)
						)
					)
					(width 0)
					(fill yes)
				)
			)
		)
		(pad "2" smd custom
			(at 0 0.4445 90)
			(size 0.1524 0.1524)
			(layers "F.Cu" "F.Mask" "F.Paste")
			(net "GND")
			(options
				(clearance outline)
				(anchor circle)
			)
			(primitives
				(gr_poly
					(pts
						(arc
							(start 0.3048 -0.2032)
							(mid 0.275042 -0.275042)
							(end 0.2032 -0.3048)
						)
						(arc
							(start -0.2032 -0.3048)
							(mid -0.275042 -0.275042)
							(end -0.3048 -0.2032)
						)
						(arc
							(start -0.3048 0.2032)
							(mid -0.275042 0.275042)
							(end -0.2032 0.3048)
						)
						(arc
							(start 0.2032 0.3048)
							(mid 0.275042 0.275042)
							(end 0.3048 0.2032)
						)
					)
					(width 0)
					(fill yes)
				)
			)
		)
	)
	(footprint ""
		(layer "F.Cu")
		(at 77.5208 -303.7205)
		(property "Reference" "R9966"
			(at 0 0 0)
			(layer "F.SilkS")
			(hide yes)
			(effects
				(font
					(size 1.27 1.27)
				)
			)
		)
		(property "Value" "56R2F-1-GP"
			(at 0.064008 -3.993896 0)
			(unlocked yes)
			(layer "F.Fab")
			(hide yes)
			(effects
				(font
					(size 1.016 1.016)
					(thickness 0.1524)
				)
			)
		)
		(property "Device Type" "R402H16"
			(at 0.064008 -5.517896 0)
			(unlocked yes)
			(layer "F.Fab")
			(hide yes)
			(effects
				(font
					(size 1.016 1.016)
					(thickness 0.1524)
				)
			)
		)
		(duplicate_pad_numbers_are_jumpers no)
		(fp_line
			(start -0.508 -0.9398)
			(end -0.508 0.9398)
			(stroke
				(width 0.1524)
				(type default)
			)
			(layer "F.SilkS")
		)
		(fp_line
			(start 0.508 -0.9398)
			(end -0.508 -0.9398)
			(stroke
				(width 0.1524)
				(type default)
			)
			(layer "F.SilkS")
		)
		(fp_rect
			(start -0.508 0.9398)
			(end 0.508 -0.9398)
			(stroke
				(width 0)
				(type default)
			)
			(fill no)
			(layer "F.CrtYd")
		)
		(fp_rect
			(start -0.508 0.9398)
			(end 0.508 -0.9398)
			(stroke
				(width 0)
				(type default)
			)
			(fill no)
			(layer "F.Fab")
		)
		(pad "1" smd custom
			(at 0 -0.4445)
			(size 0.1397 0.1397)
			(layers "F.Cu" "F.Mask" "F.Paste")
			(net "PE_100M_CLK3_N")
			(options
				(clearance outline)
				(anchor circle)
			)
			(primitives
				(gr_poly
					(pts
						(arc
							(start -0.1778 -0.2794)
							(mid -0.249642 -0.249642)
							(end -0.2794 -0.1778)
						)
						(arc
							(start -0.2794 0.1778)
							(mid -0.249642 0.249642)
							(end -0.1778 0.2794)
						)
						(arc
							(start 0.1778 0.2794)
							(mid 0.249642 0.249642)
							(end 0.2794 0.1778)
						)
						(arc
							(start 0.2794 -0.1778)
							(mid 0.249642 -0.249642)
							(end 0.1778 -0.2794)
						)
					)
					(width 0)
					(fill yes)
				)
			)
		)
		(pad "2" smd custom
			(at 0 0.4445)
			(size 0.1397 0.1397)
			(layers "F.Cu" "F.Mask" "F.Paste")
			(net "GND")
			(options
				(clearance outline)
				(anchor circle)
			)
			(primitives
				(gr_poly
					(pts
						(arc
							(start -0.1778 -0.2794)
							(mid -0.249642 -0.249642)
							(end -0.2794 -0.1778)
						)
						(arc
							(start -0.2794 0.1778)
							(mid -0.249642 0.249642)
							(end -0.1778 0.2794)
						)
						(arc
							(start 0.1778 0.2794)
							(mid 0.249642 0.249642)
							(end 0.2794 0.1778)
						)
						(arc
							(start 0.2794 -0.1778)
							(mid 0.249642 -0.249642)
							(end 0.1778 -0.2794)
						)
					)
					(width 0)
					(fill yes)
				)
			)
		)
	)
	(footprint ""
		(layer "F.Cu")
		(at 213.741 -454.66 180)
		(property "Reference" "R315"
			(at 0 0 180)
			(layer "F.SilkS")
			(hide yes)
			(effects
				(font
					(size 1.27 1.27)
				)
			)
		)
		(property "Value" "4K7R2F-GP"
			(at 0.064008 -3.993896 180)
			(unlocked yes)
			(layer "F.Fab")
			(hide yes)
			(effects
				(font
					(size 1.016 1.016)
					(thickness 0.1524)
				)
			)
		)
		(property "Device Type" "R402H16"
			(at 0.064008 -5.517896 180)
			(unlocked yes)
			(layer "F.Fab")
			(hide yes)
			(effects
				(font
					(size 1.016 1.016)
					(thickness 0.1524)
				)
			)
		)
		(duplicate_pad_numbers_are_jumpers no)
		(fp_line
			(start 0.508 -0.9398)
			(end -0.508 -0.9398)
			(stroke
				(width 0.1524)
				(type default)
			)
			(layer "F.SilkS")
		)
		(fp_line
			(start -0.508 -0.9398)
			(end -0.508 0.9398)
			(stroke
				(width 0.1524)
				(type default)
			)
			(layer "F.SilkS")
		)
		(fp_rect
			(start -0.508 0.9398)
			(end 0.508 -0.9398)
			(stroke
				(width 0)
				(type default)
			)
			(fill no)
			(layer "F.CrtYd")
		)
		(fp_rect
			(start -0.508 0.9398)
			(end 0.508 -0.9398)
			(stroke
				(width 0)
				(type default)
			)
			(fill no)
			(layer "F.Fab")
		)
		(pad "1" smd custom
			(at 0 -0.4445 180)
			(size 0.1397 0.1397)
			(layers "F.Cu" "F.Mask" "F.Paste")
			(net "P3V3")
			(options
				(clearance outline)
				(anchor circle)
			)
			(primitives
				(gr_poly
					(pts
						(arc
							(start -0.1778 -0.2794)
							(mid -0.249642 -0.249642)
							(end -0.2794 -0.1778)
						)
						(arc
							(start -0.2794 0.1778)
							(mid -0.249642 0.249642)
							(end -0.1778 0.2794)
						)
						(arc
							(start 0.1778 0.2794)
							(mid 0.249642 0.249642)
							(end 0.2794 0.1778)
						)
						(arc
							(start 0.2794 -0.1778)
							(mid 0.249642 -0.249642)
							(end 0.1778 -0.2794)
						)
					)
					(width 0)
					(fill yes)
				)
			)
		)
		(pad "2" smd custom
			(at 0 0.4445 180)
			(size 0.1397 0.1397)
			(layers "F.Cu" "F.Mask" "F.Paste")
			(net "I2C_B_TMP2_A2")
			(options
				(clearance outline)
				(anchor circle)
			)
			(primitives
				(gr_poly
					(pts
						(arc
							(start -0.1778 -0.2794)
							(mid -0.249642 -0.249642)
							(end -0.2794 -0.1778)
						)
						(arc
							(start -0.2794 0.1778)
							(mid -0.249642 0.249642)
							(end -0.1778 0.2794)
						)
						(arc
							(start 0.1778 0.2794)
							(mid 0.249642 0.249642)
							(end 0.2794 0.1778)
						)
						(arc
							(start 0.2794 -0.1778)
							(mid 0.249642 -0.249642)
							(end 0.1778 -0.2794)
						)
					)
					(width 0)
					(fill yes)
				)
			)
		)
	)
	(footprint ""
		(layer "F.Cu")
		(at 27.0256 -316.6872 180)
		(property "Reference" "PC1221"
			(at 0 0 180)
			(layer "F.SilkS")
			(hide yes)
			(effects
				(font
					(size 1.27 1.27)
				)
			)
		)
		(property "Value" "SC22U25V6KX-GP-U"
			(at -2.860802 -5.279644 180)
			(unlocked yes)
			(layer "F.Fab")
			(hide yes)
			(effects
				(font
					(size 1.016 1.016)
					(thickness 0.1524)
				)
			)
		)
		(property "Device Type" "C1206-TO0D3H75"
			(at -2.860802 -6.803644 180)
			(unlocked yes)
			(layer "F.Fab")
			(hide yes)
			(effects
				(font
					(size 1.016 1.016)
					(thickness 0.1524)
				)
			)
		)
		(duplicate_pad_numbers_are_jumpers no)
		(fp_line
			(start 1.3081 2.3749)
			(end -1.3081 2.3749)
			(stroke
				(width 0.1524)
				(type default)
			)
			(layer "F.SilkS")
		)
		(fp_line
			(start 1.3081 -2.3749)
			(end 1.3081 2.3749)
			(stroke
				(width 0.1524)
				(type default)
			)
			(layer "F.SilkS")
		)
		(fp_line
			(start -1.3081 2.3749)
			(end -1.3081 -2.3749)
			(stroke
				(width 0.1524)
				(type default)
			)
			(layer "F.SilkS")
		)
		(fp_line
			(start -1.3081 -2.3749)
			(end 1.3081 -2.3749)
			(stroke
				(width 0.1524)
				(type default)
			)
			(layer "F.SilkS")
		)
		(fp_rect
			(start -0.8001 1.6002)
			(end 0.8001 -1.6002)
			(stroke
				(width 0)
				(type default)
			)
			(fill no)
			(layer "F.CrtYd")
		)
		(fp_poly
			(pts
				(xy -1.5621 2.4511) (xy -1.5621 1.6002) (xy 0.8001 1.6002) (xy 0.8001 -1.6002) (xy -0.8001 -1.6002)
				(xy -0.8001 1.5875) (xy -1.5621 1.5875) (xy -1.5621 -2.4511) (xy 1.5621 -2.4511) (xy 1.5621 2.4511)
			)
			(stroke
				(width 0)
				(type default)
			)
			(fill no)
			(layer "F.CrtYd")
		)
		(fp_rect
			(start -1.5621 2.4511)
			(end 1.5621 -2.4511)
			(stroke
				(width 0)
				(type default)
			)
			(fill no)
			(layer "F.Fab")
		)
		(pad "1" smd rect
			(at 0 -1.392936 180)
			(size 2.1082 1.4478)
			(layers "F.Cu" "F.Mask" "F.Paste")
			(net "P12V_SSD11")
		)
		(pad "2" smd rect
			(at 0 1.392936 180)
			(size 2.1082 1.4478)
			(layers "F.Cu" "F.Mask" "F.Paste")
			(net "GND")
		)
	)
	(footprint ""
		(layer "F.Cu")
		(at 19.7485 -264.81913 180)
		(property "Reference" "R9863"
			(at 0 0 180)
			(layer "F.SilkS")
			(hide yes)
			(effects
				(font
					(size 1.27 1.27)
				)
			)
		)
		(property "Value" "0R2J-2-GP"
			(at 0.064008 -3.993896 180)
			(unlocked yes)
			(layer "F.Fab")
			(hide yes)
			(effects
				(font
					(size 1.016 1.016)
					(thickness 0.1524)
				)
			)
		)
		(property "Device Type" "R402H16"
			(at 0.064008 -5.517896 180)
			(unlocked yes)
			(layer "F.Fab")
			(hide yes)
			(effects
				(font
					(size 1.016 1.016)
					(thickness 0.1524)
				)
			)
		)
		(duplicate_pad_numbers_are_jumpers no)
		(fp_line
			(start 0.508 -0.9398)
			(end -0.508 -0.9398)
			(stroke
				(width 0.1524)
				(type default)
			)
			(layer "F.SilkS")
		)
		(fp_line
			(start -0.508 -0.9398)
			(end -0.508 0.9398)
			(stroke
				(width 0.1524)
				(type default)
			)
			(layer "F.SilkS")
		)
		(fp_rect
			(start -0.508 0.9398)
			(end 0.508 -0.9398)
			(stroke
				(width 0)
				(type default)
			)
			(fill no)
			(layer "F.CrtYd")
		)
		(fp_rect
			(start -0.508 0.9398)
			(end 0.508 -0.9398)
			(stroke
				(width 0)
				(type default)
			)
			(fill no)
			(layer "F.Fab")
		)
		(pad "1" smd custom
			(at 0 -0.4445 180)
			(size 0.1397 0.1397)
			(layers "F.Cu" "F.Mask" "F.Paste")
			(net "SSD_ACT_DR12_R")
			(options
				(clearance outline)
				(anchor circle)
			)
			(primitives
				(gr_poly
					(pts
						(arc
							(start -0.1778 -0.2794)
							(mid -0.249642 -0.249642)
							(end -0.2794 -0.1778)
						)
						(arc
							(start -0.2794 0.1778)
							(mid -0.249642 0.249642)
							(end -0.1778 0.2794)
						)
						(arc
							(start 0.1778 0.2794)
							(mid 0.249642 0.249642)
							(end 0.2794 0.1778)
						)
						(arc
							(start 0.2794 -0.1778)
							(mid 0.249642 -0.249642)
							(end 0.1778 -0.2794)
						)
					)
					(width 0)
					(fill yes)
				)
			)
		)
		(pad "2" smd custom
			(at 0 0.4445 180)
			(size 0.1397 0.1397)
			(layers "F.Cu" "F.Mask" "F.Paste")
			(net "SSD_ACT_DR12")
			(options
				(clearance outline)
				(anchor circle)
			)
			(primitives
				(gr_poly
					(pts
						(arc
							(start -0.1778 -0.2794)
							(mid -0.249642 -0.249642)
							(end -0.2794 -0.1778)
						)
						(arc
							(start -0.2794 0.1778)
							(mid -0.249642 0.249642)
							(end -0.1778 0.2794)
						)
						(arc
							(start 0.1778 0.2794)
							(mid 0.249642 0.249642)
							(end 0.2794 0.1778)
						)
						(arc
							(start 0.2794 -0.1778)
							(mid 0.249642 -0.249642)
							(end 0.1778 -0.2794)
						)
					)
					(width 0)
					(fill yes)
				)
			)
		)
	)
	(footprint ""
		(layer "F.Cu")
		(at 39.7764 -9.2964 90)
		(property "Reference" "R9870"
			(at 0 0 90)
			(layer "F.SilkS")
			(hide yes)
			(effects
				(font
					(size 1.27 1.27)
				)
			)
		)
		(property "Value" "2K2R5F-GP"
			(at 0 -8.9535 90)
			(unlocked yes)
			(layer "F.Fab")
			(hide yes)
			(effects
				(font
					(size 1.27 1.016)
					(thickness 0.1524)
				)
			)
		)
		(property "Device Type" "R805H24"
			(at 0 -10.6299 90)
			(unlocked yes)
			(layer "F.Fab")
			(hide yes)
			(effects
				(font
					(size 1.27 1.016)
					(thickness 0.1524)
				)
			)
		)
		(duplicate_pad_numbers_are_jumpers no)
		(fp_line
			(start 0.889 -1.7018)
			(end -0.889 -1.7018)
			(stroke
				(width 0.1524)
				(type default)
			)
			(layer "F.SilkS")
		)
		(fp_line
			(start 0.889 -1.7018)
			(end 0.889 -0.381)
			(stroke
				(width 0.1524)
				(type default)
			)
			(layer "F.SilkS")
		)
		(fp_line
			(start -0.889 -1.7018)
			(end -0.889 0.2794)
			(stroke
				(width 0.1524)
				(type default)
			)
			(layer "F.SilkS")
		)
		(fp_line
			(start -0.889 0.0762)
			(end -0.889 1.7018)
			(stroke
				(width 0.1524)
				(type default)
			)
			(layer "F.SilkS")
		)
		(fp_line
			(start 0.889 1.7018)
			(end 0.889 -0.508)
			(stroke
				(width 0.1524)
				(type default)
			)
			(layer "F.SilkS")
		)
		(fp_line
			(start -0.889 1.7018)
			(end 0.889 1.7018)
			(stroke
				(width 0.1524)
				(type default)
			)
			(layer "F.SilkS")
		)
		(fp_poly
			(pts
				(xy 0.9652 -1.778) (xy 0.9652 1.778) (xy -0.9652 1.778) (xy -0.9652 -1.778)
			)
			(stroke
				(width 0)
				(type default)
			)
			(fill no)
			(layer "F.CrtYd")
		)
		(fp_rect
			(start -0.9652 1.778)
			(end 0.9652 -1.778)
			(stroke
				(width 0)
				(type default)
			)
			(fill no)
			(layer "F.Fab")
		)
		(pad "1" smd rect
			(at 0 -0.9652 90)
			(size 1.397 1.143)
			(layers "F.Cu" "F.Mask" "F.Paste")
			(net "P12V_SSD14")
		)
		(pad "2" smd rect
			(at 0 0.9652 90)
			(size 1.397 1.143)
			(layers "F.Cu" "F.Mask" "F.Paste")
			(net "P12V_MOST14_GATE_D")
		)
	)
	(footprint ""
		(layer "F.Cu")
		(at 51.943 -7.747)
		(property "Reference" "R9755"
			(at 0 0 0)
			(layer "F.SilkS")
			(hide yes)
			(effects
				(font
					(size 1.27 1.27)
				)
			)
		)
		(property "Value" "4K7R2J-2-GP"
			(at 0.064008 -3.993896 0)
			(unlocked yes)
			(layer "F.Fab")
			(hide yes)
			(effects
				(font
					(size 1.016 1.016)
					(thickness 0.1524)
				)
			)
		)
		(property "Device Type" "R402H16"
			(at 0.064008 -5.517896 0)
			(unlocked yes)
			(layer "F.Fab")
			(hide yes)
			(effects
				(font
					(size 1.016 1.016)
					(thickness 0.1524)
				)
			)
		)
		(duplicate_pad_numbers_are_jumpers no)
		(fp_line
			(start -0.508 -0.9398)
			(end -0.508 0.9398)
			(stroke
				(width 0.1524)
				(type default)
			)
			(layer "F.SilkS")
		)
		(fp_line
			(start 0.508 -0.9398)
			(end -0.508 -0.9398)
			(stroke
				(width 0.1524)
				(type default)
			)
			(layer "F.SilkS")
		)
		(fp_rect
			(start -0.508 0.9398)
			(end 0.508 -0.9398)
			(stroke
				(width 0)
				(type default)
			)
			(fill no)
			(layer "F.CrtYd")
		)
		(fp_rect
			(start -0.508 0.9398)
			(end 0.508 -0.9398)
			(stroke
				(width 0)
				(type default)
			)
			(fill no)
			(layer "F.Fab")
		)
		(pad "1" smd custom
			(at 0 -0.4445)
			(size 0.1397 0.1397)
			(layers "F.Cu" "F.Mask" "F.Paste")
			(net "P3V3")
			(options
				(clearance outline)
				(anchor circle)
			)
			(primitives
				(gr_poly
					(pts
						(arc
							(start -0.1778 -0.2794)
							(mid -0.249642 -0.249642)
							(end -0.2794 -0.1778)
						)
						(arc
							(start -0.2794 0.1778)
							(mid -0.249642 0.249642)
							(end -0.1778 0.2794)
						)
						(arc
							(start 0.1778 0.2794)
							(mid 0.249642 0.249642)
							(end 0.2794 0.1778)
						)
						(arc
							(start 0.2794 -0.1778)
							(mid 0.249642 -0.249642)
							(end 0.1778 -0.2794)
						)
					)
					(width 0)
					(fill yes)
				)
			)
		)
		(pad "2" smd custom
			(at 0 0.4445)
			(size 0.1397 0.1397)
			(layers "F.Cu" "F.Mask" "F.Paste")
			(net "SSD14_PWREN")
			(options
				(clearance outline)
				(anchor circle)
			)
			(primitives
				(gr_poly
					(pts
						(arc
							(start -0.1778 -0.2794)
							(mid -0.249642 -0.249642)
							(end -0.2794 -0.1778)
						)
						(arc
							(start -0.2794 0.1778)
							(mid -0.249642 0.249642)
							(end -0.1778 0.2794)
						)
						(arc
							(start 0.1778 0.2794)
							(mid 0.249642 0.249642)
							(end 0.2794 0.1778)
						)
						(arc
							(start 0.2794 -0.1778)
							(mid 0.249642 -0.249642)
							(end 0.1778 -0.2794)
						)
					)
					(width 0)
					(fill yes)
				)
			)
		)
	)
)
